# TIMECARD (Time Appliance Project (Time Card)) — schematic netlist excerpt (pin names and nets, part order shuffled) for the footprints in the layout excerpt that follows; sources: Cadence DE-HDL packaged netlist, KiCad conversion of R4006-B0001-02_R01.brd

U22  NCP45560IMNTWG_H_DFN12  pkg DFN13_118_P0197_TR071X096  page 31
  VIN_1  = XP3R3V
  EN  = XP3R3V_FPGA_EN_R
  VCC  = XP3R3V
  GND  = SG
  SR  = XP3R3V_FPGA_SR
  PG  = UNNAMED_515_NCP45560IMNTWGHDFN1
  BLEED  = XP3R3V_FPGA
  VOUT_1  = XP3R3V_FPGA
  VOUT_2  = XP3R3V_FPGA
  VOUT_3  = XP3R3V_FPGA
  VOUT_4  = XP3R3V_FPGA
  VOUT_5  = XP3R3V_FPGA
  VIN_2  = XP3R3V

(kicad_pcb
	(version 20260206)
	(generator "pcbnew")
	(generator_version "10.0")
	(general
		(thickness 1.6)
		(legacy_teardrops no)
	)
	(paper "A4")
	(title_block
		(title "timecard-production-celestica-r4006 — R4006-B0001-02_R01.brd")
		(comment 1 "Time Appliance Project (Time Card) / footprints 295-295 of 1113")
	)
	(layers
		(0 "F.Cu" signal "TOP")
		(4 "In1.Cu" signal "L02_GND1")
		(6 "In2.Cu" signal "L03_SIG1")
		(8 "In3.Cu" signal "L04_GND2")
		(10 "In4.Cu" signal "L05_VCC1")
		(12 "In5.Cu" signal "L06_VCC2")
		(14 "In6.Cu" signal "L07_GND3")
		(16 "In7.Cu" signal "L08_SIG2")
		(18 "In8.Cu" signal "L09_GND4")
		(2 "B.Cu" signal "BOTTOM")
		(9 "F.Adhes" user "F.Adhesive")
		(11 "B.Adhes" user "B.Adhesive")
		(13 "F.Paste" user "Package Geometry/Pastemask Top")
		(15 "B.Paste" user "Package Geometry/Pastemask Bottom")
		(5 "F.SilkS" user "Ref Des/Silkscreen Top")
		(7 "B.SilkS" user "Ref Des/Silkscreen Bottom")
		(1 "F.Mask" user "Board Geometry/Soldermask Top")
		(3 "B.Mask" user "Board Geometry/Soldermask Bottom")
		(17 "Dwgs.User" user "User.Drawings")
		(19 "Cmts.User" user "User.Comments")
		(21 "Eco1.User" user "User.Eco1")
		(23 "Eco2.User" user "User.Eco2")
		(25 "Edge.Cuts" user "Board Geometry/Outline")
		(27 "Margin" user)
		(31 "F.CrtYd" user "Package Geometry/Place Bound Top")
		(29 "B.CrtYd" user "Package Geometry/Place Bound Bottom")
		(35 "F.Fab" user "Ref Des/Assembly Top")
		(33 "B.Fab" user "Ref Des/Assembly Bottom")
	)
	(footprint ""
		(layer "F.Cu")
		(at 110.6424 -73.0504 180)
		(property "Reference" "U22"
			(at 0.4064 2.47523 0)
			(unlocked yes)
			(layer "F.SilkS")
			(effects
				(font
					(size 0.7874 0.5842)
					(thickness 0.1524)
				)
			)
		)
		(property "Value" ""
			(at 0 0 180)
			(layer "F.Fab")
			(effects
				(font
					(size 1.27 1.27)
				)
			)
		)
		(property "Device Type" "NCP45560IMNTWG_H_DFN12-G222-10A"
			(at 0.074168 3.118866 180)
			(unlocked yes)
			(layer "F.Fab")
			(hide yes)
			(effects
				(font
					(size 0.7874 0.5842)
					(thickness 0.1524)
				)
			)
		)
		(property "User Part Number" "PARTNUM*"
			(at 0.074168 4.312666 180)
			(unlocked yes)
			(layer "Cmts.User")
			(hide yes)
			(effects
				(font
					(size 0.7874 0.5842)
					(thickness 0.1524)
				)
			)
		)
		(duplicate_pad_numbers_are_jumpers no)
		(fp_line
			(start 2.29235 1.754124)
			(end -2.29235 1.754124)
			(stroke
				(width 0.1)
				(type default)
			)
			(layer "F.SilkS")
		)
		(fp_line
			(start 2.29235 -1.783334)
			(end 2.29235 1.754124)
			(stroke
				(width 0.1)
				(type default)
			)
			(layer "F.SilkS")
		)
		(fp_line
			(start -2.29235 1.754124)
			(end -2.29235 -1.783334)
			(stroke
				(width 0.1)
				(type default)
			)
			(layer "F.SilkS")
		)
		(fp_line
			(start -2.29235 -1.783334)
			(end 2.29235 -1.783334)
			(stroke
				(width 0.1)
				(type default)
			)
			(layer "F.SilkS")
		)
		(fp_poly
			(pts
				(arc
					(start -3.7846 -1.930146)
					(mid -2.769108 -1.930146)
					(end -3.7846 -1.930146)
				)
			)
			(stroke
				(width 0)
				(type default)
			)
			(fill yes)
			(layer "F.SilkS")
		)
		(fp_rect
			(start 0.1016 -0.1016)
			(end 0.9017 -1.2192)
			(stroke
				(width 0)
				(type default)
			)
			(fill yes)
			(layer "F.Paste")
		)
		(fp_rect
			(start -0.9017 1.2192)
			(end -0.1016 0.1016)
			(stroke
				(width 0)
				(type default)
			)
			(fill yes)
			(layer "F.Paste")
		)
		(fp_poly
			(pts
				(xy 0.9017 0.1016)
				(arc
					(start 0.9017 0.9652)
					(mid 0.468095 0.785595)
					(end 0.6477 1.2192)
				)
				(xy 0.1016 1.2192) (xy 0.1016 0.1016)
			)
			(stroke
				(width 0)
				(type default)
			)
			(fill yes)
			(layer "F.Paste")
		)
		(fp_poly
			(pts
				(xy -0.9017 -0.1016)
				(arc
					(start -0.9017 -0.9652)
					(mid -0.468095 -0.785595)
					(end -0.6477 -1.2192)
				)
				(xy -0.1016 -1.2192) (xy -0.1016 -0.1016)
			)
			(stroke
				(width 0)
				(type default)
			)
			(fill yes)
			(layer "F.Paste")
		)
		(fp_poly
			(pts
				(xy -2.54635 2.008124) (xy 2.54635 2.008124) (xy 2.54635 -2.037334) (xy -2.54635 -2.037334)
			)
			(stroke
				(width 0)
				(type default)
			)
			(fill no)
			(layer "F.CrtYd")
		)
		(fp_line
			(start 1.500124 1.500124)
			(end 1.500124 -1.500124)
			(stroke
				(width 0.1)
				(type default)
			)
			(layer "F.Fab")
		)
		(fp_line
			(start 1.500124 -1.500124)
			(end -1.500124 -1.500124)
			(stroke
				(width 0.1)
				(type default)
			)
			(layer "F.Fab")
		)
		(fp_line
			(start -1.500124 1.500124)
			(end 1.500124 1.500124)
			(stroke
				(width 0.1)
				(type default)
			)
			(layer "F.Fab")
		)
		(fp_line
			(start -1.500124 -1.500124)
			(end -1.500124 1.500124)
			(stroke
				(width 0.1)
				(type default)
			)
			(layer "F.Fab")
		)
		(fp_poly
			(pts
				(arc
					(start -3.2766 -1.803146)
					(mid -2.261108 -1.803146)
					(end -3.2766 -1.803146)
				)
			)
			(stroke
				(width 0)
				(type default)
			)
			(fill yes)
			(layer "F.Fab")
		)
		(fp_text user "7"
			(at 2.8194 2.02565 0)
			(unlocked yes)
			(layer "F.SilkS")
			(effects
				(font
					(size 0.635 0.4064)
					(thickness 0.1524)
				)
			)
		)
		(fp_text user "12"
			(at 2.3114 -2.34315 0)
			(unlocked yes)
			(layer "F.SilkS")
			(effects
				(font
					(size 0.635 0.4064)
					(thickness 0.1524)
				)
			)
		)
		(fp_text user "6"
			(at -3.1496 1.21285 0)
			(unlocked yes)
			(layer "F.SilkS")
			(effects
				(font
					(size 0.635 0.4064)
					(thickness 0.1524)
				)
			)
		)
		(fp_text user "12"
			(at 2.6924 -1.96977 0)
			(unlocked yes)
			(layer "F.Fab")
			(effects
				(font
					(size 0.7874 0.5842)
					(thickness 0.1524)
				)
			)
		)
		(fp_text user "7"
			(at 2.5654 1.58623 0)
			(unlocked yes)
			(layer "F.Fab")
			(effects
				(font
					(size 0.7874 0.5842)
					(thickness 0.1524)
				)
			)
		)
		(fp_text user "6"
			(at -2.758948 1.418336 0)
			(unlocked yes)
			(layer "F.Fab")
			(effects
				(font
					(size 0.7874 0.5842)
					(thickness 0.1524)
				)
			)
		)
		(pad "1" smd rect
			(at -1.61925 -1.313434 180)
			(size 0.8382 0.4318)
			(layers "F.Cu" "F.Mask" "F.Paste")
			(net "XP3R3V")
		)
		(pad "2" smd rect
			(at -1.61925 -0.750062 180)
			(size 0.8382 0.3048)
			(layers "F.Cu" "F.Mask" "F.Paste")
			(net "XP3R3V_FPGA_EN_R")
		)
		(pad "3" smd rect
			(at -1.61925 -0.249936 180)
			(size 0.8382 0.3048)
			(layers "F.Cu" "F.Mask" "F.Paste")
			(net "XP3R3V")
		)
		(pad "4" smd rect
			(at -1.61925 0.249936 180)
			(size 0.8382 0.3048)
			(layers "F.Cu" "F.Mask" "F.Paste")
			(net "SG")
		)
		(pad "5" smd rect
			(at -1.61925 0.750062 180)
			(size 0.8382 0.3048)
			(layers "F.Cu" "F.Mask" "F.Paste")
			(net "XP3R3V_FPGA_SR")
		)
		(pad "6" smd rect
			(at -1.61925 1.249934 180)
			(size 0.8382 0.3048)
			(layers "F.Cu" "F.Mask" "F.Paste")
			(net "UNNAMED_515_NCP45560IMNTWGHDFN1")
		)
		(pad "7" smd rect
			(at 1.61925 1.249934 180)
			(size 0.8382 0.3048)
			(layers "F.Cu" "F.Mask" "F.Paste")
			(net "XP3R3V_FPGA")
		)
		(pad "8" smd rect
			(at 1.61925 0.750062 180)
			(size 0.8382 0.3048)
			(layers "F.Cu" "F.Mask" "F.Paste")
			(net "XP3R3V_FPGA")
		)
		(pad "9" smd rect
			(at 1.61925 0.249936 180)
			(size 0.8382 0.3048)
			(layers "F.Cu" "F.Mask" "F.Paste")
			(net "XP3R3V_FPGA")
		)
		(pad "10" smd rect
			(at 1.61925 -0.249936 180)
			(size 0.8382 0.3048)
			(layers "F.Cu" "F.Mask" "F.Paste")
			(net "XP3R3V_FPGA")
		)
		(pad "11" smd rect
			(at 1.61925 -0.750062 180)
			(size 0.8382 0.3048)
			(layers "F.Cu" "F.Mask" "F.Paste")
			(net "XP3R3V_FPGA")
		)
		(pad "12" smd rect
			(at 1.61925 -1.249934 180)
			(size 0.8382 0.3048)
			(layers "F.Cu" "F.Mask" "F.Paste")
			(net "XP3R3V_FPGA")
		)
		(pad "13" smd rect
			(at 0 0 180)
			(size 1.8034 2.4384)
			(layers "F.Cu" "F.Mask" "F.Paste")
			(net "XP3R3V")
		)
	)
)
